(kicad_pcb
	(version 20241229)
	(generator "pcbnew")
	(generator_version "9.0")
	(general
		(thickness 1.599998)
		(legacy_teardrops no)
	)
	(paper "A4")
	(title_block
		(title "Artix - Datacenter Secure Control Module (DC-SCM)")
		(date "2024-11-06")
		(rev "1.1.3")
		(comment 9 "footprints 93-93 of 544")
	)
	(layers
		(0 "F.Cu" signal)
		(4 "In1.Cu" signal)
		(6 "In2.Cu" signal)
		(8 "In3.Cu" signal)
		(10 "In4.Cu" signal)
		(12 "In5.Cu" signal)
		(14 "In6.Cu" signal)
		(2 "B.Cu" signal)
		(9 "F.Adhes" user "F.Adhesive")
		(11 "B.Adhes" user "B.Adhesive")
		(13 "F.Paste" user)
		(15 "B.Paste" user)
		(5 "F.SilkS" user "F.Silkscreen")
		(7 "B.SilkS" user "B.Silkscreen")
		(1 "F.Mask" user)
		(3 "B.Mask" user)
		(17 "Dwgs.User" user "User.Drawings")
		(19 "Cmts.User" user "User.Comments")
		(21 "Eco1.User" user "User.Eco1")
		(23 "Eco2.User" user "User.Eco2")
		(25 "Edge.Cuts" user)
		(27 "Margin" user)
		(31 "F.CrtYd" user "F.Courtyard")
		(29 "B.CrtYd" user "B.Courtyard")
		(35 "F.Fab" user)
		(33 "B.Fab" user)
	)
	(footprint "antmicro-footprints:QFN-48-1EP_7x7x0.9mm_P0.5mm_EP3.5x3.5mm"
		(layer "F.Cu")
		(at 102.1 96.225 -90)
		(property "Reference" "U20"
			(at -4.285 -4.08 270)
			(layer "F.SilkS")
			(effects
				(font
					(size 0.7 0.7)
					(thickness 0.15)
				)
				(justify left bottom)
			)
		)
		(property "Value" "KSZ9031RNXCA"
			(at 0 5.1 270)
			(layer "F.Fab")
			(hide yes)
			(effects
				(font
					(size 0.7 0.7)
					(thickness 0.15)
				)
				(justify left bottom)
			)
		)
		(property "Datasheet" "http://ww1.microchip.com/downloads/en/DeviceDoc/00002117F.pdf"
			(at 0 0 270)
			(layer "F.Fab")
			(hide yes)
			(effects
				(font
					(size 1.27 1.27)
					(thickness 0.15)
				)
			)
		)
		(property "Description" "Ethernet Controller, 1000 Mbps, IEEE 802.3, 1.14 V, 3.465 V, QFN, 48 Pins"
			(at 0 0 270)
			(layer "F.Fab")
			(hide yes)
			(effects
				(font
					(size 1.27 1.27)
					(thickness 0.15)
				)
			)
		)
		(property "Author" "Antmicro"
			(at 5.875 198.325 0)
			(layer "F.Fab")
			(hide yes)
			(effects
				(font
					(size 1 1)
					(thickness 0.15)
				)
			)
		)
		(property "License" "Apache-2.0"
			(at 5.875 198.325 0)
			(layer "F.Fab")
			(hide yes)
			(effects
				(font
					(size 1 1)
					(thickness 0.15)
				)
			)
		)
		(property "MPN" "KSZ9031RNXCA"
			(at 5.875 198.325 0)
			(layer "F.Fab")
			(hide yes)
			(effects
				(font
					(size 1 1)
					(thickness 0.15)
				)
			)
		)
		(property "Manufacturer" "Microchip Technology"
			(at 5.875 198.325 0)
			(layer "F.Fab")
			(hide yes)
			(effects
				(font
					(size 1 1)
					(thickness 0.15)
				)
			)
		)
		(sheetname "/Ethernet/")
		(sheetfile "ethernet.kicad_sch")
		(attr smd)
		(fp_line
			(start -3.65 3.648)
			(end -3.65 3.249)
			(stroke
				(width 0.15)
				(type solid)
			)
			(layer "F.SilkS")
		)
		(fp_line
			(start -3.25 3.648)
			(end -3.65 3.648)
			(stroke
				(width 0.15)
				(type solid)
			)
			(layer "F.SilkS")
		)
		(fp_line
			(start 3.249 3.648)
			(end 3.648 3.648)
			(stroke
				(width 0.15)
				(type solid)
			)
			(layer "F.SilkS")
		)
		(fp_line
			(start 3.648 3.648)
			(end 3.648 3.249)
			(stroke
				(width 0.15)
				(type solid)
			)
			(layer "F.SilkS")
		)
		(fp_line
			(start -3.65 -3.3)
			(end -3.65 -3.65)
			(stroke
				(width 0.15)
				(type solid)
			)
			(layer "F.SilkS")
		)
		(fp_line
			(start -3.3 -3.65)
			(end -3.65 -3.65)
			(stroke
				(width 0.15)
				(type solid)
			)
			(layer "F.SilkS")
		)
		(fp_line
			(start 3.249 -3.65)
			(end 3.648 -3.65)
			(stroke
				(width 0.15)
				(type solid)
			)
			(layer "F.SilkS")
		)
		(fp_line
			(start 3.648 -3.65)
			(end 3.648 -3.25)
			(stroke
				(width 0.15)
				(type solid)
			)
			(layer "F.SilkS")
		)
		(fp_circle
			(center -3.7 -3.05)
			(end -3.65 -3.05)
			(stroke
				(width 0.15)
				(type solid)
			)
			(fill yes)
			(layer "F.SilkS")
		)
		(fp_rect
			(start -4.15 -4.15)
			(end 4.15 4.15)
			(stroke
				(width 0.05)
				(type solid)
			)
			(fill no)
			(layer "F.CrtYd")
		)
		(fp_line
			(start -3.5 3.499)
			(end 3.499 3.499)
			(stroke
				(width 0.15)
				(type solid)
			)
			(layer "F.Fab")
		)
		(fp_line
			(start 3.499 3.499)
			(end 3.499 -3.5)
			(stroke
				(width 0.15)
				(type solid)
			)
			(layer "F.Fab")
		)
		(fp_line
			(start -3.5 -2.5)
			(end -3.5 3.499)
			(stroke
				(width 0.15)
				(type solid)
			)
			(layer "F.Fab")
		)
		(fp_line
			(start -2.5 -3.5)
			(end -3.5 -2.5)
			(stroke
				(width 0.15)
				(type solid)
			)
			(layer "F.Fab")
		)
		(fp_line
			(start 3.499 -3.5)
			(end -2.5 -3.5)
			(stroke
				(width 0.15)
				(type solid)
			)
			(layer "F.Fab")
		)
		(pad "1" smd oval
			(at -3.5 -2.75)
			(size 0.3 0.9)
			(layers "F.Cu" "F.Mask" "F.Paste")
			(net 406 "/Ethernet/AVDDH")
			(pinfunction "AVDDH")
			(pintype "power_in")
		)
		(pad "2" smd oval
			(at -3.5 -2.25)
			(size 0.3 0.9)
			(layers "F.Cu" "F.Mask" "F.Paste")
			(net 435 "/Ethernet/ETH1_P")
			(pinfunction "TXRXP_A")
			(pintype "bidirectional")
		)
		(pad "3" smd oval
			(at -3.5 -1.75)
			(size 0.3 0.9)
			(layers "F.Cu" "F.Mask" "F.Paste")
			(net 434 "/Ethernet/ETH1_N")
			(pinfunction "TXRXM_A")
			(pintype "bidirectional")
		)
		(pad "4" smd oval
			(at -3.5 -1.25)
			(size 0.3 0.9)
			(layers "F.Cu" "F.Mask" "F.Paste")
			(net 405 "/Ethernet/AVDDL")
			(pinfunction "AVDDL")
			(pintype "power_in")
		)
		(pad "5" smd oval
			(at -3.5 -0.75)
			(size 0.3 0.9)
			(layers "F.Cu" "F.Mask" "F.Paste")
			(net 433 "/Ethernet/ETH2_P")
			(pinfunction "TXRXP_B")
			(pintype "bidirectional")
		)
		(pad "6" smd oval
			(at -3.5 -0.25)
			(size 0.3 0.9)
			(layers "F.Cu" "F.Mask" "F.Paste")
			(net 432 "/Ethernet/ETH2_N")
			(pinfunction "TXRXM_B")
			(pintype "bidirectional")
		)
		(pad "7" smd oval
			(at -3.5 0.248)
			(size 0.3 0.9)
			(layers "F.Cu" "F.Mask" "F.Paste")
			(net 431 "/Ethernet/ETH3_P")
			(pinfunction "TXRXP_C")
			(pintype "bidirectional")
		)
		(pad "8" smd oval
			(at -3.5 0.748)
			(size 0.3 0.9)
			(layers "F.Cu" "F.Mask" "F.Paste")
			(net 430 "/Ethernet/ETH3_N")
			(pinfunction "TXRXM_C")
			(pintype "bidirectional")
		)
		(pad "9" smd oval
			(at -3.5 1.249)
			(size 0.3 0.9)
			(layers "F.Cu" "F.Mask" "F.Paste")
			(net 405 "/Ethernet/AVDDL")
			(pinfunction "AVDDL")
			(pintype "passive")
		)
		(pad "10" smd oval
			(at -3.5 1.749)
			(size 0.3 0.9)
			(layers "F.Cu" "F.Mask" "F.Paste")
			(net 429 "/Ethernet/ETH4_P")
			(pinfunction "TXRXP_D")
			(pintype "bidirectional")
		)
		(pad "11" smd oval
			(at -3.5 2.249)
			(size 0.3 0.9)
			(layers "F.Cu" "F.Mask" "F.Paste")
			(net 428 "/Ethernet/ETH4_N")
			(pinfunction "TXRXM_D")
			(pintype "bidirectional")
		)
		(pad "12" smd oval
			(at -3.5 2.749)
			(size 0.3 0.9)
			(layers "F.Cu" "F.Mask" "F.Paste")
			(net 406 "/Ethernet/AVDDH")
			(pinfunction "AVDDH")
			(pintype "passive")
		)
		(pad "13" smd oval
			(at -2.75 3.499 270)
			(size 0.3 0.9)
			(layers "F.Cu" "F.Mask" "F.Paste")
			(net 687 "unconnected-(U20-NC-Pad13)")
			(pinfunction "NC")
			(pintype "no_connect")
		)
		(pad "14" smd oval
			(at -2.25 3.499 270)
			(size 0.3 0.9)
			(layers "F.Cu" "F.Mask" "F.Paste")
			(net 339 "VCC1V2")
			(pinfunction "DVDDL")
			(pintype "power_in")
		)
		(pad "15" smd oval
			(at -1.75 3.499 270)
			(size 0.3 0.9)
			(layers "F.Cu" "F.Mask" "F.Paste")
			(net 416 "/Ethernet/ETH_LED2")
			(pinfunction "LED2/PHYAD1")
			(pintype "bidirectional")
		)
		(pad "16" smd oval
			(at -1.25 3.499 270)
			(size 0.3 0.9)
			(layers "F.Cu" "F.Mask" "F.Paste")
			(net 2 "VCC3V3")
			(pinfunction "DVDDH")
			(pintype "power_in")
		)
		(pad "17" smd oval
			(at -0.75 3.499 270)
			(size 0.3 0.9)
			(layers "F.Cu" "F.Mask" "F.Paste")
			(net 415 "/Ethernet/ETH_LED1")
			(pinfunction "LED1/PHYAD0/PME_N1")
			(pintype "bidirectional")
		)
		(pad "18" smd oval
			(at -0.25 3.499 270)
			(size 0.3 0.9)
			(layers "F.Cu" "F.Mask" "F.Paste")
			(net 339 "VCC1V2")
			(pinfunction "DVDDL")
			(pintype "passive")
		)
		(pad "19" smd oval
			(at 0.248 3.499 270)
			(size 0.3 0.9)
			(layers "F.Cu" "F.Mask" "F.Paste")
			(net 425 "RGMII_TXD0")
			(pinfunction "TXD0")
			(pintype "input")
		)
		(pad "20" smd oval
			(at 0.748 3.499 270)
			(size 0.3 0.9)
			(layers "F.Cu" "F.Mask" "F.Paste")
			(net 424 "RGMII_TXD1")
			(pinfunction "TXD1")
			(pintype "input")
		)
		(pad "21" smd oval
			(at 1.249 3.499 270)
			(size 0.3 0.9)
			(layers "F.Cu" "F.Mask" "F.Paste")
			(net 423 "RGMII_TXD2")
			(pinfunction "TXD2")
			(pintype "input")
		)
		(pad "22" smd oval
			(at 1.749 3.499 270)
			(size 0.3 0.9)
			(layers "F.Cu" "F.Mask" "F.Paste")
			(net 422 "RGMII_TXD3")
			(pinfunction "TXD3")
			(pintype "input")
		)
		(pad "23" smd oval
			(at 2.249 3.499 270)
			(size 0.3 0.9)
			(layers "F.Cu" "F.Mask" "F.Paste")
			(net 339 "VCC1V2")
			(pinfunction "DVDDL")
			(pintype "passive")
		)
		(pad "24" smd oval
			(at 2.749 3.499 270)
			(size 0.3 0.9)
			(layers "F.Cu" "F.Mask" "F.Paste")
			(net 421 "RGMII_TX_CLK")
			(pinfunction "GTX_CLK")
			(pintype "input")
		)
		(pad "25" smd oval
			(at 3.499 2.749)
			(size 0.3 0.9)
			(layers "F.Cu" "F.Mask" "F.Paste")
			(net 427 "RGMII_TX_DV")
			(pinfunction "TX_EN")
			(pintype "input")
		)
		(pad "26" smd oval
			(at 3.499 2.249)
			(size 0.3 0.9)
			(layers "F.Cu" "F.Mask" "F.Paste")
			(net 339 "VCC1V2")
			(pinfunction "DVDDL")
			(pintype "passive")
		)
		(pad "27" smd oval
			(at 3.499 1.749)
			(size 0.3 0.9)
			(layers "F.Cu" "F.Mask" "F.Paste")
			(net 410 "RGMII_RXD3")
			(pinfunction "RXD3/MODE3")
			(pintype "input")
		)
		(pad "28" smd oval
			(at 3.499 1.249)
			(size 0.3 0.9)
			(layers "F.Cu" "F.Mask" "F.Paste")
			(net 409 "RGMII_RXD2")
			(pinfunction "RXD2/MODE2")
			(pintype "input")
		)
		(pad "29" smd oval
			(at 3.499 0.748)
			(size 0.3 0.9)
			(layers "F.Cu" "F.Mask" "F.Paste")
			(net 1 "GND")
			(pinfunction "VSS")
			(pintype "power_in")
		)
		(pad "30" smd oval
			(at 3.499 0.248)
			(size 0.3 0.9)
			(layers "F.Cu" "F.Mask" "F.Paste")
			(net 339 "VCC1V2")
			(pinfunction "DVDDL")
			(pintype "passive")
		)
		(pad "31" smd oval
			(at 3.499 -0.25)
			(size 0.3 0.9)
			(layers "F.Cu" "F.Mask" "F.Paste")
			(net 408 "RGMII_RXD1")
			(pinfunction "RXD1/MODE1")
			(pintype "input")
		)
		(pad "32" smd oval
			(at 3.499 -0.75)
			(size 0.3 0.9)
			(layers "F.Cu" "F.Mask" "F.Paste")
			(net 407 "RGMII_RXD0")
			(pinfunction "RXD0/MODE0")
			(pintype "input")
		)
		(pad "33" smd oval
			(at 3.499 -1.25)
			(size 0.3 0.9)
			(layers "F.Cu" "F.Mask" "F.Paste")
			(net 411 "RGMII_RX_DV")
			(pinfunction "RX_DV/CLK125_EN")
			(pintype "input")
		)
		(pad "34" smd oval
			(at 3.499 -1.75)
			(size 0.3 0.9)
			(layers "F.Cu" "F.Mask" "F.Paste")
			(net 2 "VCC3V3")
			(pinfunction "DVDDH")
			(pintype "passive")
		)
		(pad "35" smd oval
			(at 3.499 -2.25)
			(size 0.3 0.9)
			(layers "F.Cu" "F.Mask" "F.Paste")
			(net 412 "RGMII_RX_CLK")
			(pinfunction "RX_CLK/PHYAD2")
			(pintype "input")
		)
		(pad "36" smd oval
			(at 3.499 -2.75)
			(size 0.3 0.9)
			(layers "F.Cu" "F.Mask" "F.Paste")
			(net 141 "ETH_MDC")
			(pinfunction "MDC")
			(pintype "input")
		)
		(pad "37" smd oval
			(at 2.749 -3.5 270)
			(size 0.3 0.9)
			(layers "F.Cu" "F.Mask" "F.Paste")
			(net 142 "ETH_MDIO")
			(pinfunction "MDIO")
			(pintype "input")
		)
		(pad "38" smd oval
			(at 2.249 -3.5 270)
			(size 0.3 0.9)
			(layers "F.Cu" "F.Mask" "F.Paste")
			(net 420 "ETH_INT_N")
			(pinfunction "~{INT/PME}")
			(pintype "input")
		)
		(pad "39" smd oval
			(at 1.749 -3.5 270)
			(size 0.3 0.9)
			(layers "F.Cu" "F.Mask" "F.Paste")
			(net 339 "VCC1V2")
			(pinfunction "DVDDL")
			(pintype "passive")
		)
		(pad "40" smd oval
			(at 1.249 -3.5 270)
			(size 0.3 0.9)
			(layers "F.Cu" "F.Mask" "F.Paste")
			(net 2 "VCC3V3")
			(pinfunction "DVDDH")
			(pintype "passive")
		)
		(pad "41" smd oval
			(at 0.748 -3.5 270)
			(size 0.3 0.9)
			(layers "F.Cu" "F.Mask" "F.Paste")
			(net 413 "RGMII_REF_CLK")
			(pinfunction "CLK125_NDO/LED_MODE")
			(pintype "input")
		)
		(pad "42" smd oval
			(at 0.248 -3.5 270)
			(size 0.3 0.9)
			(layers "F.Cu" "F.Mask" "F.Paste")
			(net 414 "ETH_~{RESET}")
			(pinfunction "~{RESET}")
			(pintype "input")
		)
		(pad "43" smd oval
			(at -0.25 -3.5 270)
			(size 0.3 0.9)
			(layers "F.Cu" "F.Mask" "F.Paste")
			(net 688 "unconnected-(U20-LDO_O-Pad43)")
			(pinfunction "LDO_O")
			(pintype "input+no_connect")
		)
		(pad "44" smd oval
			(at -0.75 -3.5 270)
			(size 0.3 0.9)
			(layers "F.Cu" "F.Mask" "F.Paste")
			(net 404 "/Ethernet/AVDDL_PLL")
			(pinfunction "AVDDL_PLL")
			(pintype "power_in")
		)
		(pad "45" smd oval
			(at -1.25 -3.5 270)
			(size 0.3 0.9)
			(layers "F.Cu" "F.Mask" "F.Paste")
			(net 199 "Net-(U20-XO)")
			(pinfunction "XO")
			(pintype "input")
		)
		(pad "46" smd oval
			(at -1.75 -3.5 270)
			(size 0.3 0.9)
			(layers "F.Cu" "F.Mask" "F.Paste")
			(net 201 "Net-(U20-XI)")
			(pinfunction "XI")
			(pintype "input")
		)
		(pad "47" smd oval
			(at -2.25 -3.5 270)
			(size 0.3 0.9)
			(layers "F.Cu" "F.Mask" "F.Paste")
			(net 689 "unconnected-(U20-NC-Pad47)")
			(pinfunction "NC")
			(pintype "no_connect")
		)
		(pad "48" smd oval
			(at -2.75 -3.5 270)
			(size 0.3 0.9)
			(layers "F.Cu" "F.Mask" "F.Paste")
			(net 345 "Net-(U20-ISET)")
			(pinfunction "ISET")
			(pintype "output")
		)
		(pad "49" smd rect
			(at 0 0 270)
			(size 3.5 3.5)
			(layers "F.Cu" "F.Mask" "F.Paste")
			(net 1 "GND")
			(pinfunction "PAD_GND")
			(pintype "power_in")
		)
	)
)
